# T6G (Grand Teton) — schematic netlist excerpt (pin names and nets, part order shuffled) for the footprints in the layout excerpt that follows; sources: Cadence DE-HDL packaged netlist, KiCad conversion of 04192023_DAF0TMB3IC0_F0TG_MB_C_brd_V02_OCP.brd

DB6  TDR_3P  EMPTY  pkg TH2  page 260
  GND  = T1_GND
  IO1  = TDR_SE_45_OHM_BOT
  IO2  = TDR_SE_45_OHM_BOT

C205  Q_CAP  0.1UF 10V 10% X7S  pkg C0201  page 334 : A = P1V8_CPU1_RT1_1A ; B = GND
C541  Q_CAP  0.1UF 10V 10% X7S  pkg C0201  page 279 : A = P0V9_CPU0_RT0_2A ; B = GND
R691  Q_RES  49.9 1% CHIP  pkg 0201LF  page 342 : A = SMB_RT_CPU1_P2_ROM_MUX_1D_SCL ; B = SMB_RT_CPU1_P2_ROM_MUX_1D_R_SCL

(kicad_pcb
	(version 20260206)
	(generator "pcbnew")
	(generator_version "10.0")
	(general
		(thickness 1.6)
		(legacy_teardrops no)
	)
	(paper "A4")
	(title_block
		(title "04192023_DAF0TMB3IC0_F0TG_MB_C_brd_V02_OCP.brd")
		(comment 1 "Grand Teton / footprints 7924-7927 of 8354")
	)
	(layers
		(0 "F.Cu" signal "TOP")
		(4 "In1.Cu" signal "GND")
		(6 "In2.Cu" signal "IN1")
		(8 "In3.Cu" signal "GND1")
		(10 "In4.Cu" signal "IN2")
		(12 "In5.Cu" signal "GND2")
		(14 "In6.Cu" signal "IN3")
		(16 "In7.Cu" signal "GND3")
		(18 "In8.Cu" signal "VCC")
		(20 "In9.Cu" signal "VCC1")
		(22 "In10.Cu" signal "GND4")
		(24 "In11.Cu" signal "IN4")
		(26 "In12.Cu" signal "GND5")
		(28 "In13.Cu" signal "IN5")
		(30 "In14.Cu" signal "GND6")
		(32 "In15.Cu" signal "IN6")
		(34 "In16.Cu" signal "GND7")
		(2 "B.Cu" signal "BOTTOM")
		(9 "F.Adhes" user "F.Adhesive")
		(11 "B.Adhes" user "B.Adhesive")
		(13 "F.Paste" user "Package Geometry/Pastemask Top")
		(15 "B.Paste" user "Package Geometry/Pastemask Bottom")
		(5 "F.SilkS" user "Ref Des/Silkscreen Top")
		(7 "B.SilkS" user "Ref Des/Silkscreen Bottom")
		(1 "F.Mask" user "Board Geometry/Soldermask Top")
		(3 "B.Mask" user "Board Geometry/Soldermask Bottom")
		(17 "Dwgs.User" user "User.Drawings")
		(19 "Cmts.User" user "User.Comments")
		(21 "Eco1.User" user "User.Eco1")
		(23 "Eco2.User" user "User.Eco2")
		(25 "Edge.Cuts" user "Board Geometry/Outline")
		(27 "Margin" user)
		(31 "F.CrtYd" user "Package Geometry/Place Bound Top")
		(29 "B.CrtYd" user "Package Geometry/Place Bound Bottom")
		(35 "F.Fab" user "Ref Des/Assembly Top")
		(33 "B.Fab" user "Ref Des/Assembly Bottom")
	)
	(footprint ""
		(layer "B.Cu")
		(at 474.16466 -297.49877 180)
		(property "Reference" "DB6"
			(at 2.845308 -7.762748 270)
			(unlocked yes)
			(layer "B.SilkS")
			(effects
				(font
					(size 0.7874 0.5842)
					(thickness 0.1524)
				)
				(justify left mirror)
			)
		)
		(property "Value" ""
			(at 0 0 0)
			(layer "B.Fab")
			(effects
				(font
					(size 1.27 1.27)
				)
				(justify mirror)
			)
		)
		(duplicate_pad_numbers_are_jumpers no)
		(fp_line
			(start 3.330702 -4.771136)
			(end -3.330702 -4.771136)
			(stroke
				(width 0.1524)
				(type default)
			)
			(layer "B.SilkS")
		)
		(fp_line
			(start 0 4.011168)
			(end 3.330702 -4.771136)
			(stroke
				(width 0.1524)
				(type default)
			)
			(layer "B.SilkS")
		)
		(fp_line
			(start -3.330702 -4.771136)
			(end 0 4.011168)
			(stroke
				(width 0.1524)
				(type default)
			)
			(layer "B.SilkS")
		)
		(fp_line
			(start 3.330702 -4.771136)
			(end -3.330702 -4.771136)
			(stroke
				(width 0.1)
				(type default)
			)
			(layer "B.Fab")
		)
		(fp_line
			(start 0 4.011168)
			(end 3.330702 -4.771136)
			(stroke
				(width 0.1)
				(type default)
			)
			(layer "B.Fab")
		)
		(fp_line
			(start -3.330702 -4.771136)
			(end 0 4.011168)
			(stroke
				(width 0.1)
				(type default)
			)
			(layer "B.Fab")
		)
		(pad "1" thru_hole circle
			(at 0 0)
			(size 2.159 2.159)
			(drill 1.7018)
			(layers "*.Cu" "*.Mask")
			(remove_unused_layers no)
			(net "T1_GND")
			(clearance 0.0254)
			(thermal_gap 0.0254)
		)
		(pad "2" thru_hole circle
			(at 1.27 -3.348736)
			(size 2.159 2.159)
			(drill 1.7018)
			(layers "*.Cu" "*.Mask")
			(remove_unused_layers no)
			(net "TDR_SE_45_OHM_BOT")
			(clearance 0.0254)
			(thermal_gap 0.0254)
		)
		(pad "3" thru_hole circle
			(at -1.27 -3.348736)
			(size 2.159 2.159)
			(drill 1.7018)
			(layers "*.Cu" "*.Mask")
			(remove_unused_layers no)
			(net "TDR_SE_45_OHM_BOT")
			(clearance 0.0254)
			(thermal_gap 0.0254)
		)
	)
	(footprint ""
		(layer "B.Cu")
		(at 163.46932 -413.5374 90)
		(property "Reference" "R691"
			(at 0 0 90)
			(layer "B.SilkS")
			(hide yes)
			(effects
				(font
					(size 1.27 1.27)
				)
				(justify mirror)
			)
		)
		(property "Value" ""
			(at 0 0 90)
			(layer "B.Fab")
			(effects
				(font
					(size 1.27 1.27)
				)
				(justify mirror)
			)
		)
		(duplicate_pad_numbers_are_jumpers no)
		(fp_line
			(start 0.32512 -0.175006)
			(end -0.32512 -0.175006)
			(stroke
				(width 0.1)
				(type default)
			)
			(layer "B.Fab")
		)
		(fp_line
			(start -0.32512 -0.175006)
			(end -0.32512 0.175006)
			(stroke
				(width 0.1)
				(type default)
			)
			(layer "B.Fab")
		)
		(fp_line
			(start 0.32512 0.175006)
			(end 0.32512 -0.175006)
			(stroke
				(width 0.1)
				(type default)
			)
			(layer "B.Fab")
		)
		(fp_line
			(start -0.32512 0.175006)
			(end 0.32512 0.175006)
			(stroke
				(width 0.1)
				(type default)
			)
			(layer "B.Fab")
		)
		(pad "1" smd rect
			(at 0.2667 0 270)
			(size 0.3048 0.381)
			(layers "B.Cu" "B.Mask" "B.Paste")
			(net "SMB_RT_CPU1_P2_ROM_MUX_1D_SCL")
		)
		(pad "2" smd rect
			(at -0.2667 0 90)
			(size 0.3048 0.381)
			(layers "B.Cu" "B.Mask" "B.Paste")
			(net "SMB_RT_CPU1_P2_ROM_MUX_1D_R_SCL")
		)
	)
	(footprint ""
		(layer "B.Cu")
		(at 320.318384 -396.393162 -90)
		(property "Reference" "C541"
			(at 0 0 90)
			(layer "B.SilkS")
			(hide yes)
			(effects
				(font
					(size 1.27 1.27)
				)
				(justify mirror)
			)
		)
		(property "Value" ""
			(at 0 0 90)
			(layer "B.Fab")
			(effects
				(font
					(size 1.27 1.27)
				)
				(justify mirror)
			)
		)
		(duplicate_pad_numbers_are_jumpers no)
		(fp_line
			(start -0.299974 0.150114)
			(end 0.299974 0.150114)
			(stroke
				(width 0.1)
				(type default)
			)
			(layer "B.Fab")
		)
		(fp_line
			(start 0.299974 0.150114)
			(end 0.299974 -0.150114)
			(stroke
				(width 0.1)
				(type default)
			)
			(layer "B.Fab")
		)
		(fp_line
			(start -0.299974 -0.150114)
			(end -0.299974 0.150114)
			(stroke
				(width 0.1)
				(type default)
			)
			(layer "B.Fab")
		)
		(fp_line
			(start 0.299974 -0.150114)
			(end -0.299974 -0.150114)
			(stroke
				(width 0.1)
				(type default)
			)
			(layer "B.Fab")
		)
		(pad "1" smd rect
			(at 0.2667 0 90)
			(size 0.3048 0.381)
			(layers "B.Cu" "B.Mask" "B.Paste")
			(net "P0V9_CPU0_RT0_2A")
		)
		(pad "2" smd rect
			(at -0.2667 0 90)
			(size 0.3048 0.381)
			(layers "B.Cu" "B.Mask" "B.Paste")
			(net "GND")
		)
	)
	(footprint ""
		(layer "B.Cu")
		(at 87.106252 -386.766562 90)
		(property "Reference" "C205"
			(at 0 0 90)
			(layer "B.SilkS")
			(hide yes)
			(effects
				(font
					(size 1.27 1.27)
				)
				(justify mirror)
			)
		)
		(property "Value" ""
			(at 0 0 90)
			(layer "B.Fab")
			(effects
				(font
					(size 1.27 1.27)
				)
				(justify mirror)
			)
		)
		(duplicate_pad_numbers_are_jumpers no)
		(fp_line
			(start 0.299974 -0.150114)
			(end -0.299974 -0.150114)
			(stroke
				(width 0.1)
				(type default)
			)
			(layer "B.Fab")
		)
		(fp_line
			(start -0.299974 -0.150114)
			(end -0.299974 0.150114)
			(stroke
				(width 0.1)
				(type default)
			)
			(layer "B.Fab")
		)
		(fp_line
			(start 0.299974 0.150114)
			(end 0.299974 -0.150114)
			(stroke
				(width 0.1)
				(type default)
			)
			(layer "B.Fab")
		)
		(fp_line
			(start -0.299974 0.150114)
			(end 0.299974 0.150114)
			(stroke
				(width 0.1)
				(type default)
			)
			(layer "B.Fab")
		)
		(pad "1" smd rect
			(at 0.2667 0 270)
			(size 0.3048 0.381)
			(layers "B.Cu" "B.Mask" "B.Paste")
			(net "P1V8_CPU1_RT1_1A")
		)
		(pad "2" smd rect
			(at -0.2667 0 270)
			(size 0.3048 0.381)
			(layers "B.Cu" "B.Mask" "B.Paste")
			(net "GND")
		)
	)
)
